FILE_TYPE = MACRO_DRAWING;
SET COLOR_WIRE YELLOW;
SET COLOR_PROP ORANGE;
SET COLOR_DOT WHITE;
SET COLOR_ARC YELLOW;
SET COLOR_BODY GREEN;
SET COLOR_NOTE PURPLE;
SET PROP_DISPLAY VALUE;
SET PAGE_NUMBER P448;
FORCEADD PT5161LRS..6
(-7700 4375);
FORCEPROP 1 LAST LOCATION U6016
J 0
(-8050 6000);
DISPLAY 0.723404 (-8050 6000);
PAINT GREEN (-8050 6000);
FORCEPROP 0 LAST $SEC 6
J 0
(-8050 6150);
DISPLAY 0.680851 (-8050 6150);
PAINT MONO (-8050 6150);
DISPLAY INVISIBLE (-8050 6150);
FORCEPROP 0 LAST CDS_SEC 6
J 0
(-8050 6150);
DISPLAY 0.680851 (-8050 6150);
DISPLAY INVISIBLE (-8050 6150);
FORCEPROP 0 LASTPIN (-7250 5525) $PN P29
J 0
(-7240 5535);
DISPLAY 0.680851 (-7240 5535);
PAINT MONO (-7240 5535);
FORCEPROP 0 LASTPIN (-7250 5175) $PN AA29
J 0
(-7240 5185);
DISPLAY 0.680851 (-7240 5185);
PAINT MONO (-7240 5185);
FORCEPROP 0 LASTPIN (-7250 4825) $PN AH29
J 0
(-7240 4835);
DISPLAY 0.680851 (-7240 4835);
PAINT MONO (-7240 4835);
FORCEPROP 0 LASTPIN (-7250 4475) $PN AR29
J 0
(-7240 4485);
DISPLAY 0.680851 (-7240 4485);
PAINT MONO (-7240 4485);
FORCEPROP 0 LASTPIN (-7250 4125) $PN BB29
J 0
(-7240 4135);
DISPLAY 0.680851 (-7240 4135);
PAINT MONO (-7240 4135);
FORCEPROP 0 LASTPIN (-7250 3775) $PN BJ29
J 0
(-7240 3785);
DISPLAY 0.680851 (-7240 3785);
PAINT MONO (-7240 3785);
FORCEPROP 0 LASTPIN (-7250 3425) $PN BT29
J 0
(-7240 3435);
DISPLAY 0.680851 (-7240 3435);
PAINT MONO (-7240 3435);
FORCEPROP 0 LASTPIN (-7250 3075) $PN CC29
J 0
(-7240 3085);
DISPLAY 0.680851 (-7240 3085);
PAINT MONO (-7240 3085);
FORCEPROP 0 LASTPIN (-7250 5625) $PN M26
J 0
(-7240 5635);
DISPLAY 0.680851 (-7240 5635);
PAINT MONO (-7240 5635);
FORCEPROP 0 LASTPIN (-7250 5275) $PN W26
J 0
(-7240 5285);
DISPLAY 0.680851 (-7240 5285);
PAINT MONO (-7240 5285);
FORCEPROP 0 LASTPIN (-7250 4925) $PN AF26
J 0
(-7240 4935);
DISPLAY 0.680851 (-7240 4935);
PAINT MONO (-7240 4935);
FORCEPROP 0 LASTPIN (-7250 4575) $PN AN26
J 0
(-7240 4585);
DISPLAY 0.680851 (-7240 4585);
PAINT MONO (-7240 4585);
FORCEPROP 0 LASTPIN (-7250 4225) $PN AY26
J 0
(-7240 4235);
DISPLAY 0.680851 (-7240 4235);
PAINT MONO (-7240 4235);
FORCEPROP 0 LASTPIN (-7250 3875) $PN BG26
J 0
(-7240 3885);
DISPLAY 0.680851 (-7240 3885);
PAINT MONO (-7240 3885);
FORCEPROP 0 LASTPIN (-7250 3525) $PN BP26
J 0
(-7240 3535);
DISPLAY 0.680851 (-7240 3535);
PAINT MONO (-7240 3535);
FORCEPROP 0 LASTPIN (-7250 3175) $PN CA26
J 0
(-7240 3185);
DISPLAY 0.680851 (-7240 3185);
PAINT MONO (-7240 3185);
FORCEPROP 1 LAST MATERIAL IC
J 0
(-8050 5850);
DISPLAY 0.723404 (-8050 5850);
PAINT GREEN (-8050 5850);
FORCEPROP 2 LAST PART_TYPE SMLF
J 0
(-8050 6100);
DISPLAY 0.680851 (-8050 6100);
FORCEPROP 2 LAST VALUE PT5161LRS
J 0
(-8050 6050);
DISPLAY 0.680851 (-8050 6050);
FORCEPROP 2 LAST CDS_LIB pure_quanta
J 0
(-7700 4375);
DISPLAY INVISIBLE (-7700 4375);
FORCEPROP 1 LAST CDS_LMAN_SYM_OUTLINE -350,1450,300,-1400
J 0
(-7700 4375);
DISPLAY 0.468085 (-7700 4375);
PAINT GREEN (-7700 4375);
DISPLAY INVISIBLE (-7700 4375);
FORCEPROP 1 LAST NEEDS_NO_SIZE TRUE
J 0
(-7700 4375);
DISPLAY 0.723404 (-7700 4375);
PAINT GREEN (-7700 4375);
DISPLAY INVISIBLE (-7700 4375);
FORCEPROP 1 LAST PATH I1
J 0
(-7700 4375);
DISPLAY 0.723404 (-7700 4375);
PAINT GREEN (-7700 4375);
DISPLAY INVISIBLE (-7700 4375);
FORCEPROP 1 LAST PART_NUMBER AJ051610U03
J 0
(-8050 5925);
DISPLAY 0.723404 (-8050 5925);
PAINT GREEN (-8050 5925);
DISPLAY INVISIBLE (-8050 5925);
FORCEADD TAP..1
(-6475 4475);
FORCEPROP 3 LASTPIN (-6525 4475) SIG_NAME P5E_CPU1_P2_RX_DN<12>
J 0
(-6515 4485);
DISPLAY 0.659574 (-6515 4485);
PAINT MONO (-6515 4485);
DISPLAY INVISIBLE (-6515 4485);
FORCEPROP 1 LASTPIN (-6525 4475) BN 12
J 0
(-6537 4483);
DISPLAY 0.680851 (-6537 4483);
PAINT GREEN (-6537 4483);
FORCEPROP 2 LAST CDS_LIB standard
J 0
(-6475 4475);
DISPLAY INVISIBLE (-6475 4475);
FORCEPROP 1 LAST BODY_TYPE PLUMBING
J 0
(-6475 4525);
DISPLAY 0.872340 (-6475 4525);
PAINT GREEN (-6475 4525);
DISPLAY INVISIBLE (-6475 4525);
FORCEPROP 1 LAST HDL_TAP TRUE
J 0
(-6150 4350);
DISPLAY 0.872340 (-6150 4350);
DISPLAY INVISIBLE (-6150 4350);
FORCEPROP 1 LAST PATH I10
J 0
(-6477 4475);
DISPLAY 0.872340 (-6477 4475);
PAINT GREEN (-6477 4475);
DISPLAY INVISIBLE (-6477 4475);
FORCEADD TAP..1
(-6675 4575);
FORCEPROP 3 LASTPIN (-6725 4575) SIG_NAME P5E_CPU1_P2_RX_DP<12>
J 0
(-6715 4585);
DISPLAY 0.659574 (-6715 4585);
PAINT MONO (-6715 4585);
DISPLAY INVISIBLE (-6715 4585);
FORCEPROP 1 LASTPIN (-6725 4575) BN 12
J 0
(-6737 4583);
DISPLAY 0.680851 (-6737 4583);
PAINT GREEN (-6737 4583);
FORCEPROP 2 LAST CDS_LIB standard
J 0
(-6675 4575);
DISPLAY INVISIBLE (-6675 4575);
FORCEPROP 1 LAST BODY_TYPE PLUMBING
J 0
(-6675 4625);
DISPLAY 0.872340 (-6675 4625);
PAINT GREEN (-6675 4625);
DISPLAY INVISIBLE (-6675 4625);
FORCEPROP 1 LAST HDL_TAP TRUE
J 0
(-6350 4450);
DISPLAY 0.872340 (-6350 4450);
DISPLAY INVISIBLE (-6350 4450);
FORCEPROP 1 LAST PATH I11
J 0
(-6677 4575);
DISPLAY 0.872340 (-6677 4575);
PAINT GREEN (-6677 4575);
DISPLAY INVISIBLE (-6677 4575);
FORCEADD TAP..1
(-6675 4925);
FORCEPROP 3 LASTPIN (-6725 4925) SIG_NAME P5E_CPU1_P2_RX_DP<13>
J 0
(-6715 4935);
DISPLAY 0.659574 (-6715 4935);
PAINT MONO (-6715 4935);
DISPLAY INVISIBLE (-6715 4935);
FORCEPROP 1 LASTPIN (-6725 4925) BN 13
J 0
(-6737 4933);
DISPLAY 0.680851 (-6737 4933);
PAINT GREEN (-6737 4933);
FORCEPROP 2 LAST CDS_LIB standard
J 0
(-6675 4925);
DISPLAY INVISIBLE (-6675 4925);
FORCEPROP 1 LAST BODY_TYPE PLUMBING
J 0
(-6675 4975);
DISPLAY 0.872340 (-6675 4975);
PAINT GREEN (-6675 4975);
DISPLAY INVISIBLE (-6675 4975);
FORCEPROP 1 LAST HDL_TAP TRUE
J 0
(-6350 4800);
DISPLAY 0.872340 (-6350 4800);
DISPLAY INVISIBLE (-6350 4800);
FORCEPROP 1 LAST PATH I12
J 0
(-6677 4925);
DISPLAY 0.872340 (-6677 4925);
PAINT GREEN (-6677 4925);
DISPLAY INVISIBLE (-6677 4925);
FORCEADD TAP..1
(-6475 4825);
FORCEPROP 3 LASTPIN (-6525 4825) SIG_NAME P5E_CPU1_P2_RX_DN<13>
J 0
(-6515 4835);
DISPLAY 0.659574 (-6515 4835);
PAINT MONO (-6515 4835);
DISPLAY INVISIBLE (-6515 4835);
FORCEPROP 1 LASTPIN (-6525 4825) BN 13
J 0
(-6537 4833);
DISPLAY 0.680851 (-6537 4833);
PAINT GREEN (-6537 4833);
FORCEPROP 2 LAST CDS_LIB standard
J 0
(-6475 4825);
DISPLAY INVISIBLE (-6475 4825);
FORCEPROP 1 LAST BODY_TYPE PLUMBING
J 0
(-6475 4875);
DISPLAY 0.872340 (-6475 4875);
PAINT GREEN (-6475 4875);
DISPLAY INVISIBLE (-6475 4875);
FORCEPROP 1 LAST HDL_TAP TRUE
J 0
(-6150 4700);
DISPLAY 0.872340 (-6150 4700);
DISPLAY INVISIBLE (-6150 4700);
FORCEPROP 1 LAST PATH I13
J 0
(-6477 4825);
DISPLAY 0.872340 (-6477 4825);
PAINT GREEN (-6477 4825);
DISPLAY INVISIBLE (-6477 4825);
FORCEADD TAP..1
(-6675 5275);
FORCEPROP 3 LASTPIN (-6725 5275) SIG_NAME P5E_CPU1_P2_RX_DP<14>
J 0
(-6715 5285);
DISPLAY 0.659574 (-6715 5285);
PAINT MONO (-6715 5285);
DISPLAY INVISIBLE (-6715 5285);
FORCEPROP 1 LASTPIN (-6725 5275) BN 14
J 0
(-6737 5283);
DISPLAY 0.680851 (-6737 5283);
PAINT GREEN (-6737 5283);
FORCEPROP 2 LAST CDS_LIB standard
J 0
(-6675 5275);
DISPLAY INVISIBLE (-6675 5275);
FORCEPROP 1 LAST BODY_TYPE PLUMBING
J 0
(-6675 5325);
DISPLAY 0.872340 (-6675 5325);
PAINT GREEN (-6675 5325);
DISPLAY INVISIBLE (-6675 5325);
FORCEPROP 1 LAST HDL_TAP TRUE
J 0
(-6350 5150);
DISPLAY 0.872340 (-6350 5150);
DISPLAY INVISIBLE (-6350 5150);
FORCEPROP 1 LAST PATH I14
J 0
(-6677 5275);
DISPLAY 0.872340 (-6677 5275);
PAINT GREEN (-6677 5275);
DISPLAY INVISIBLE (-6677 5275);
FORCEADD TAP..1
(-6475 5175);
FORCEPROP 3 LASTPIN (-6525 5175) SIG_NAME P5E_CPU1_P2_RX_DN<14>
J 0
(-6515 5185);
DISPLAY 0.659574 (-6515 5185);
PAINT MONO (-6515 5185);
DISPLAY INVISIBLE (-6515 5185);
FORCEPROP 1 LASTPIN (-6525 5175) BN 14
J 0
(-6537 5183);
DISPLAY 0.680851 (-6537 5183);
PAINT GREEN (-6537 5183);
FORCEPROP 2 LAST CDS_LIB standard
J 0
(-6475 5175);
DISPLAY INVISIBLE (-6475 5175);
FORCEPROP 1 LAST BODY_TYPE PLUMBING
J 0
(-6475 5225);
DISPLAY 0.872340 (-6475 5225);
PAINT GREEN (-6475 5225);
DISPLAY INVISIBLE (-6475 5225);
FORCEPROP 1 LAST HDL_TAP TRUE
J 0
(-6150 5050);
DISPLAY 0.872340 (-6150 5050);
DISPLAY INVISIBLE (-6150 5050);
FORCEPROP 1 LAST PATH I15
J 0
(-6477 5175);
DISPLAY 0.872340 (-6477 5175);
PAINT GREEN (-6477 5175);
DISPLAY INVISIBLE (-6477 5175);
FORCEADD TAP..1
(-6475 5525);
FORCEPROP 3 LASTPIN (-6525 5525) SIG_NAME P5E_CPU1_P2_RX_DN<15>
J 0
(-6515 5535);
DISPLAY 0.659574 (-6515 5535);
PAINT MONO (-6515 5535);
DISPLAY INVISIBLE (-6515 5535);
FORCEPROP 1 LASTPIN (-6525 5525) BN 15
J 0
(-6537 5533);
DISPLAY 0.680851 (-6537 5533);
PAINT GREEN (-6537 5533);
FORCEPROP 2 LAST CDS_LIB standard
J 0
(-6475 5525);
DISPLAY INVISIBLE (-6475 5525);
FORCEPROP 1 LAST BODY_TYPE PLUMBING
J 0
(-6475 5575);
DISPLAY 0.872340 (-6475 5575);
PAINT GREEN (-6475 5575);
DISPLAY INVISIBLE (-6475 5575);
FORCEPROP 1 LAST HDL_TAP TRUE
J 0
(-6150 5400);
DISPLAY 0.872340 (-6150 5400);
DISPLAY INVISIBLE (-6150 5400);
FORCEPROP 1 LAST PATH I16
J 0
(-6477 5525);
DISPLAY 0.872340 (-6477 5525);
PAINT GREEN (-6477 5525);
DISPLAY INVISIBLE (-6477 5525);
FORCEADD TAP..1
(-6675 5625);
FORCEPROP 3 LASTPIN (-6725 5625) SIG_NAME P5E_CPU1_P2_RX_DP<15>
J 0
(-6715 5635);
DISPLAY 0.659574 (-6715 5635);
PAINT MONO (-6715 5635);
DISPLAY INVISIBLE (-6715 5635);
FORCEPROP 1 LASTPIN (-6725 5625) BN 15
J 0
(-6737 5633);
DISPLAY 0.680851 (-6737 5633);
PAINT GREEN (-6737 5633);
FORCEPROP 2 LAST CDS_LIB standard
J 0
(-6675 5625);
DISPLAY INVISIBLE (-6675 5625);
FORCEPROP 1 LAST BODY_TYPE PLUMBING
J 0
(-6675 5675);
DISPLAY 0.872340 (-6675 5675);
PAINT GREEN (-6675 5675);
DISPLAY INVISIBLE (-6675 5675);
FORCEPROP 1 LAST HDL_TAP TRUE
J 0
(-6350 5500);
DISPLAY 0.872340 (-6350 5500);
DISPLAY INVISIBLE (-6350 5500);
FORCEPROP 1 LAST PATH I17
J 0
(-6677 5625);
DISPLAY 0.872340 (-6677 5625);
PAINT GREEN (-6677 5625);
DISPLAY INVISIBLE (-6677 5625);
FORCEADD OFFPAGE..5
R 2
(-5450 5800);
FORCEPROP 2 LAST $XR0 52 
J 0
(-5261 5800);
DISPLAY 0.638298 (-5261 5800);
PAINT MONO (-5261 5800);
FORCEPROP 2 LAST CDS_LIB standard
J 0
(-5450 5800);
DISPLAY INVISIBLE (-5450 5800);
FORCEPROP 1 LAST OFFPAGE TRUE
J 2
(-5775 5675);
DISPLAY 0.872340 (-5775 5675);
PAINT GREEN (-5775 5675);
DISPLAY INVISIBLE (-5775 5675);
FORCEPROP 1 LAST COMMENT_BODY TRUE
J 2
(-5550 5725);
DISPLAY 0.872340 (-5550 5725);
PAINT GREEN (-5550 5725);
DISPLAY INVISIBLE (-5550 5725);
FORCEPROP 2 LAST PATH I18
J 0
(-5275 5875);
DISPLAY 0.680851 (-5275 5875);
DISPLAY INVISIBLE (-5275 5875);
FORCEADD OFFPAGE..5
R 2
(-5450 5950);
FORCEPROP 2 LAST $XR0 52 
J 0
(-5261 5950);
DISPLAY 0.638298 (-5261 5950);
PAINT MONO (-5261 5950);
FORCEPROP 2 LAST CDS_LIB standard
J 0
(-5450 5950);
DISPLAY INVISIBLE (-5450 5950);
FORCEPROP 1 LAST OFFPAGE TRUE
J 2
(-5775 5825);
DISPLAY 0.872340 (-5775 5825);
PAINT GREEN (-5775 5825);
DISPLAY INVISIBLE (-5775 5825);
FORCEPROP 1 LAST COMMENT_BODY TRUE
J 2
(-5550 5875);
DISPLAY 0.872340 (-5550 5875);
PAINT GREEN (-5550 5875);
DISPLAY INVISIBLE (-5550 5875);
FORCEPROP 2 LAST PATH I19
J 0
(-5275 6025);
DISPLAY 0.680851 (-5275 6025);
DISPLAY INVISIBLE (-5275 6025);
FORCEADD TAP..1
(-6675 3525);
FORCEPROP 3 LASTPIN (-6725 3525) SIG_NAME P5E_CPU1_P2_RX_DP<9>
J 0
(-6715 3535);
DISPLAY 0.659574 (-6715 3535);
PAINT MONO (-6715 3535);
DISPLAY INVISIBLE (-6715 3535);
FORCEPROP 1 LASTPIN (-6725 3525) BN 9
J 0
(-6737 3533);
DISPLAY 0.680851 (-6737 3533);
PAINT GREEN (-6737 3533);
FORCEPROP 2 LAST CDS_LIB standard
J 0
(-6675 3525);
DISPLAY INVISIBLE (-6675 3525);
FORCEPROP 1 LAST BODY_TYPE PLUMBING
J 0
(-6675 3575);
DISPLAY 0.872340 (-6675 3575);
PAINT GREEN (-6675 3575);
DISPLAY INVISIBLE (-6675 3575);
FORCEPROP 1 LAST HDL_TAP TRUE
J 0
(-6350 3400);
DISPLAY 0.872340 (-6350 3400);
DISPLAY INVISIBLE (-6350 3400);
FORCEPROP 1 LAST PATH I2
J 0
(-6677 3525);
DISPLAY 0.872340 (-6677 3525);
PAINT GREEN (-6677 3525);
DISPLAY INVISIBLE (-6677 3525);
FORCEADD TAP..1
(-2150 3250);
FORCEPROP 3 LASTPIN (-2200 3250) SIG_NAME P5E_CPU1_P2_RX_DP<0>
J 0
(-2190 3260);
DISPLAY 0.659574 (-2190 3260);
PAINT MONO (-2190 3260);
DISPLAY INVISIBLE (-2190 3260);
FORCEPROP 1 LASTPIN (-2200 3250) BN 0
J 0
(-2212 3258);
DISPLAY 0.680851 (-2212 3258);
PAINT GREEN (-2212 3258);
FORCEPROP 2 LAST CDS_LIB standard
J 0
(-2150 3250);
DISPLAY INVISIBLE (-2150 3250);
FORCEPROP 1 LAST BODY_TYPE PLUMBING
J 0
(-2150 3300);
DISPLAY 0.872340 (-2150 3300);
PAINT GREEN (-2150 3300);
DISPLAY INVISIBLE (-2150 3300);
FORCEPROP 1 LAST HDL_TAP TRUE
J 0
(-1825 3125);
DISPLAY 0.872340 (-1825 3125);
DISPLAY INVISIBLE (-1825 3125);
FORCEPROP 1 LAST PATH I20
J 0
(-2152 3250);
DISPLAY 0.872340 (-2152 3250);
PAINT GREEN (-2152 3250);
DISPLAY INVISIBLE (-2152 3250);
FORCEADD TAP..1
(-2150 4300);
FORCEPROP 3 LASTPIN (-2200 4300) SIG_NAME P5E_CPU1_P2_RX_DP<3>
J 0
(-2190 4310);
DISPLAY 0.659574 (-2190 4310);
PAINT MONO (-2190 4310);
DISPLAY INVISIBLE (-2190 4310);
FORCEPROP 1 LASTPIN (-2200 4300) BN 3
J 0
(-2212 4308);
DISPLAY 0.680851 (-2212 4308);
PAINT GREEN (-2212 4308);
FORCEPROP 2 LAST CDS_LIB standard
J 0
(-2150 4300);
DISPLAY INVISIBLE (-2150 4300);
FORCEPROP 1 LAST BODY_TYPE PLUMBING
J 0
(-2150 4350);
DISPLAY 0.872340 (-2150 4350);
PAINT GREEN (-2150 4350);
DISPLAY INVISIBLE (-2150 4350);
FORCEPROP 1 LAST HDL_TAP TRUE
J 0
(-1825 4175);
DISPLAY 0.872340 (-1825 4175);
DISPLAY INVISIBLE (-1825 4175);
FORCEPROP 1 LAST PATH I21
J 0
(-2152 4300);
DISPLAY 0.872340 (-2152 4300);
PAINT GREEN (-2152 4300);
DISPLAY INVISIBLE (-2152 4300);
FORCEADD TAP..1
(-2150 3950);
FORCEPROP 3 LASTPIN (-2200 3950) SIG_NAME P5E_CPU1_P2_RX_DP<2>
J 0
(-2190 3960);
DISPLAY 0.659574 (-2190 3960);
PAINT MONO (-2190 3960);
DISPLAY INVISIBLE (-2190 3960);
FORCEPROP 1 LASTPIN (-2200 3950) BN 2
J 0
(-2212 3958);
DISPLAY 0.680851 (-2212 3958);
PAINT GREEN (-2212 3958);
FORCEPROP 2 LAST CDS_LIB standard
J 0
(-2150 3950);
DISPLAY INVISIBLE (-2150 3950);
FORCEPROP 1 LAST BODY_TYPE PLUMBING
J 0
(-2150 4000);
DISPLAY 0.872340 (-2150 4000);
PAINT GREEN (-2150 4000);
DISPLAY INVISIBLE (-2150 4000);
FORCEPROP 1 LAST HDL_TAP TRUE
J 0
(-1825 3825);
DISPLAY 0.872340 (-1825 3825);
DISPLAY INVISIBLE (-1825 3825);
FORCEPROP 1 LAST PATH I22
J 0
(-2152 3950);
DISPLAY 0.872340 (-2152 3950);
PAINT GREEN (-2152 3950);
DISPLAY INVISIBLE (-2152 3950);
FORCEADD TAP..1
(-2150 3600);
FORCEPROP 3 LASTPIN (-2200 3600) SIG_NAME P5E_CPU1_P2_RX_DP<1>
J 0
(-2190 3610);
DISPLAY 0.659574 (-2190 3610);
PAINT MONO (-2190 3610);
DISPLAY INVISIBLE (-2190 3610);
FORCEPROP 1 LASTPIN (-2200 3600) BN 1
J 0
(-2212 3608);
DISPLAY 0.680851 (-2212 3608);
PAINT GREEN (-2212 3608);
FORCEPROP 2 LAST CDS_LIB standard
J 0
(-2150 3600);
DISPLAY INVISIBLE (-2150 3600);
FORCEPROP 1 LAST BODY_TYPE PLUMBING
J 0
(-2150 3650);
DISPLAY 0.872340 (-2150 3650);
PAINT GREEN (-2150 3650);
DISPLAY INVISIBLE (-2150 3650);
FORCEPROP 1 LAST HDL_TAP TRUE
J 0
(-1825 3475);
DISPLAY 0.872340 (-1825 3475);
DISPLAY INVISIBLE (-1825 3475);
FORCEPROP 1 LAST PATH I23
J 0
(-2152 3600);
DISPLAY 0.872340 (-2152 3600);
PAINT GREEN (-2152 3600);
DISPLAY INVISIBLE (-2152 3600);
FORCEADD TAP..1
(-1950 3150);
FORCEPROP 3 LASTPIN (-2000 3150) SIG_NAME P5E_CPU1_P2_RX_DN<0>
J 0
(-1990 3160);
DISPLAY 0.659574 (-1990 3160);
PAINT MONO (-1990 3160);
DISPLAY INVISIBLE (-1990 3160);
FORCEPROP 1 LASTPIN (-2000 3150) BN 0
J 0
(-2012 3158);
DISPLAY 0.680851 (-2012 3158);
PAINT GREEN (-2012 3158);
FORCEPROP 2 LAST CDS_LIB standard
J 0
(-1950 3150);
DISPLAY INVISIBLE (-1950 3150);
FORCEPROP 1 LAST BODY_TYPE PLUMBING
J 0
(-1950 3200);
DISPLAY 0.872340 (-1950 3200);
PAINT GREEN (-1950 3200);
DISPLAY INVISIBLE (-1950 3200);
FORCEPROP 1 LAST HDL_TAP TRUE
J 0
(-1625 3025);
DISPLAY 0.872340 (-1625 3025);
DISPLAY INVISIBLE (-1625 3025);
FORCEPROP 1 LAST PATH I24
J 0
(-1952 3150);
DISPLAY 0.872340 (-1952 3150);
PAINT GREEN (-1952 3150);
DISPLAY INVISIBLE (-1952 3150);
FORCEADD TAP..1
(-1950 3500);
FORCEPROP 3 LASTPIN (-2000 3500) SIG_NAME P5E_CPU1_P2_RX_DN<1>
J 0
(-1990 3510);
DISPLAY 0.659574 (-1990 3510);
PAINT MONO (-1990 3510);
DISPLAY INVISIBLE (-1990 3510);
FORCEPROP 1 LASTPIN (-2000 3500) BN 1
J 0
(-2012 3508);
DISPLAY 0.680851 (-2012 3508);
PAINT GREEN (-2012 3508);
FORCEPROP 2 LAST CDS_LIB standard
J 0
(-1950 3500);
DISPLAY INVISIBLE (-1950 3500);
FORCEPROP 1 LAST BODY_TYPE PLUMBING
J 0
(-1950 3550);
DISPLAY 0.872340 (-1950 3550);
PAINT GREEN (-1950 3550);
DISPLAY INVISIBLE (-1950 3550);
FORCEPROP 1 LAST HDL_TAP TRUE
J 0
(-1625 3375);
DISPLAY 0.872340 (-1625 3375);
DISPLAY INVISIBLE (-1625 3375);
FORCEPROP 1 LAST PATH I25
J 0
(-1952 3500);
DISPLAY 0.872340 (-1952 3500);
PAINT GREEN (-1952 3500);
DISPLAY INVISIBLE (-1952 3500);
FORCEADD TAP..1
(-1950 3850);
FORCEPROP 3 LASTPIN (-2000 3850) SIG_NAME P5E_CPU1_P2_RX_DN<2>
J 0
(-1990 3860);
DISPLAY 0.659574 (-1990 3860);
PAINT MONO (-1990 3860);
DISPLAY INVISIBLE (-1990 3860);
FORCEPROP 1 LASTPIN (-2000 3850) BN 2
J 0
(-2012 3858);
DISPLAY 0.680851 (-2012 3858);
PAINT GREEN (-2012 3858);
FORCEPROP 2 LAST CDS_LIB standard
J 0
(-1950 3850);
DISPLAY INVISIBLE (-1950 3850);
FORCEPROP 1 LAST BODY_TYPE PLUMBING
J 0
(-1950 3900);
DISPLAY 0.872340 (-1950 3900);
PAINT GREEN (-1950 3900);
DISPLAY INVISIBLE (-1950 3900);
FORCEPROP 1 LAST HDL_TAP TRUE
J 0
(-1625 3725);
DISPLAY 0.872340 (-1625 3725);
DISPLAY INVISIBLE (-1625 3725);
FORCEPROP 1 LAST PATH I26
J 0
(-1952 3850);
DISPLAY 0.872340 (-1952 3850);
PAINT GREEN (-1952 3850);
DISPLAY INVISIBLE (-1952 3850);
FORCEADD TAP..1
(-1950 4200);
FORCEPROP 3 LASTPIN (-2000 4200) SIG_NAME P5E_CPU1_P2_RX_DN<3>
J 0
(-1990 4210);
DISPLAY 0.659574 (-1990 4210);
PAINT MONO (-1990 4210);
DISPLAY INVISIBLE (-1990 4210);
FORCEPROP 1 LASTPIN (-2000 4200) BN 3
J 0
(-2012 4208);
DISPLAY 0.680851 (-2012 4208);
PAINT GREEN (-2012 4208);
FORCEPROP 2 LAST CDS_LIB standard
J 0
(-1950 4200);
DISPLAY INVISIBLE (-1950 4200);
FORCEPROP 1 LAST BODY_TYPE PLUMBING
J 0
(-1950 4250);
DISPLAY 0.872340 (-1950 4250);
PAINT GREEN (-1950 4250);
DISPLAY INVISIBLE (-1950 4250);
FORCEPROP 1 LAST HDL_TAP TRUE
J 0
(-1625 4075);
DISPLAY 0.872340 (-1625 4075);
DISPLAY INVISIBLE (-1625 4075);
FORCEPROP 1 LAST PATH I27
J 0
(-1952 4200);
DISPLAY 0.872340 (-1952 4200);
PAINT GREEN (-1952 4200);
DISPLAY INVISIBLE (-1952 4200);
FORCEADD TAP..1
(-1950 4550);
FORCEPROP 3 LASTPIN (-2000 4550) SIG_NAME P5E_CPU1_P2_RX_DN<4>
J 0
(-1990 4560);
DISPLAY 0.659574 (-1990 4560);
PAINT MONO (-1990 4560);
DISPLAY INVISIBLE (-1990 4560);
FORCEPROP 1 LASTPIN (-2000 4550) BN 4
J 0
(-2012 4558);
DISPLAY 0.680851 (-2012 4558);
PAINT GREEN (-2012 4558);
FORCEPROP 2 LAST CDS_LIB standard
J 0
(-1950 4550);
DISPLAY INVISIBLE (-1950 4550);
FORCEPROP 1 LAST BODY_TYPE PLUMBING
J 0
(-1950 4600);
DISPLAY 0.872340 (-1950 4600);
PAINT GREEN (-1950 4600);
DISPLAY INVISIBLE (-1950 4600);
FORCEPROP 1 LAST HDL_TAP TRUE
J 0
(-1625 4425);
DISPLAY 0.872340 (-1625 4425);
DISPLAY INVISIBLE (-1625 4425);
FORCEPROP 1 LAST PATH I28
J 0
(-1952 4550);
DISPLAY 0.872340 (-1952 4550);
PAINT GREEN (-1952 4550);
DISPLAY INVISIBLE (-1952 4550);
FORCEADD TAP..1
(-2150 4650);
FORCEPROP 3 LASTPIN (-2200 4650) SIG_NAME P5E_CPU1_P2_RX_DP<4>
J 0
(-2190 4660);
DISPLAY 0.659574 (-2190 4660);
PAINT MONO (-2190 4660);
DISPLAY INVISIBLE (-2190 4660);
FORCEPROP 1 LASTPIN (-2200 4650) BN 4
J 0
(-2212 4658);
DISPLAY 0.680851 (-2212 4658);
PAINT GREEN (-2212 4658);
FORCEPROP 2 LAST CDS_LIB standard
J 0
(-2150 4650);
DISPLAY INVISIBLE (-2150 4650);
FORCEPROP 1 LAST BODY_TYPE PLUMBING
J 0
(-2150 4700);
DISPLAY 0.872340 (-2150 4700);
PAINT GREEN (-2150 4700);
DISPLAY INVISIBLE (-2150 4700);
FORCEPROP 1 LAST HDL_TAP TRUE
J 0
(-1825 4525);
DISPLAY 0.872340 (-1825 4525);
DISPLAY INVISIBLE (-1825 4525);
FORCEPROP 1 LAST PATH I29
J 0
(-2152 4650);
DISPLAY 0.872340 (-2152 4650);
PAINT GREEN (-2152 4650);
DISPLAY INVISIBLE (-2152 4650);
FORCEADD TAP..1
(-6675 3175);
FORCEPROP 3 LASTPIN (-6725 3175) SIG_NAME P5E_CPU1_P2_RX_DP<8>
J 0
(-6715 3185);
DISPLAY 0.659574 (-6715 3185);
PAINT MONO (-6715 3185);
DISPLAY INVISIBLE (-6715 3185);
FORCEPROP 1 LASTPIN (-6725 3175) BN 8
J 0
(-6737 3183);
DISPLAY 0.680851 (-6737 3183);
PAINT GREEN (-6737 3183);
FORCEPROP 2 LAST CDS_LIB standard
J 0
(-6675 3175);
DISPLAY INVISIBLE (-6675 3175);
FORCEPROP 1 LAST BODY_TYPE PLUMBING
J 0
(-6675 3225);
DISPLAY 0.872340 (-6675 3225);
PAINT GREEN (-6675 3225);
DISPLAY INVISIBLE (-6675 3225);
FORCEPROP 1 LAST HDL_TAP TRUE
J 0
(-6350 3050);
DISPLAY 0.872340 (-6350 3050);
DISPLAY INVISIBLE (-6350 3050);
FORCEPROP 1 LAST PATH I3
J 0
(-6677 3175);
DISPLAY 0.872340 (-6677 3175);
PAINT GREEN (-6677 3175);
DISPLAY INVISIBLE (-6677 3175);
FORCEADD TAP..1
(-2150 5000);
FORCEPROP 3 LASTPIN (-2200 5000) SIG_NAME P5E_CPU1_P2_RX_DP<5>
J 0
(-2190 5010);
DISPLAY 0.659574 (-2190 5010);
PAINT MONO (-2190 5010);
DISPLAY INVISIBLE (-2190 5010);
FORCEPROP 1 LASTPIN (-2200 5000) BN 5
J 0
(-2212 5008);
DISPLAY 0.680851 (-2212 5008);
PAINT GREEN (-2212 5008);
FORCEPROP 2 LAST CDS_LIB standard
J 0
(-2150 5000);
DISPLAY INVISIBLE (-2150 5000);
FORCEPROP 1 LAST BODY_TYPE PLUMBING
J 0
(-2150 5050);
DISPLAY 0.872340 (-2150 5050);
PAINT GREEN (-2150 5050);
DISPLAY INVISIBLE (-2150 5050);
FORCEPROP 1 LAST HDL_TAP TRUE
J 0
(-1825 4875);
DISPLAY 0.872340 (-1825 4875);
DISPLAY INVISIBLE (-1825 4875);
FORCEPROP 1 LAST PATH I30
J 0
(-2152 5000);
DISPLAY 0.872340 (-2152 5000);
PAINT GREEN (-2152 5000);
DISPLAY INVISIBLE (-2152 5000);
FORCEADD TAP..1
(-2150 5350);
FORCEPROP 3 LASTPIN (-2200 5350) SIG_NAME P5E_CPU1_P2_RX_DP<6>
J 0
(-2190 5360);
DISPLAY 0.659574 (-2190 5360);
PAINT MONO (-2190 5360);
DISPLAY INVISIBLE (-2190 5360);
FORCEPROP 1 LASTPIN (-2200 5350) BN 6
J 0
(-2212 5358);
DISPLAY 0.680851 (-2212 5358);
PAINT GREEN (-2212 5358);
FORCEPROP 2 LAST CDS_LIB standard
J 0
(-2150 5350);
DISPLAY INVISIBLE (-2150 5350);
FORCEPROP 1 LAST BODY_TYPE PLUMBING
J 0
(-2150 5400);
DISPLAY 0.872340 (-2150 5400);
PAINT GREEN (-2150 5400);
DISPLAY INVISIBLE (-2150 5400);
FORCEPROP 1 LAST HDL_TAP TRUE
J 0
(-1825 5225);
DISPLAY 0.872340 (-1825 5225);
DISPLAY INVISIBLE (-1825 5225);
FORCEPROP 1 LAST PATH I31
J 0
(-2152 5350);
DISPLAY 0.872340 (-2152 5350);
PAINT GREEN (-2152 5350);
DISPLAY INVISIBLE (-2152 5350);
FORCEADD TAP..1
(-2150 5700);
FORCEPROP 3 LASTPIN (-2200 5700) SIG_NAME P5E_CPU1_P2_RX_DP<7>
J 0
(-2190 5710);
DISPLAY 0.659574 (-2190 5710);
PAINT MONO (-2190 5710);
DISPLAY INVISIBLE (-2190 5710);
FORCEPROP 1 LASTPIN (-2200 5700) BN 7
J 0
(-2212 5708);
DISPLAY 0.680851 (-2212 5708);
PAINT GREEN (-2212 5708);
FORCEPROP 2 LAST CDS_LIB standard
J 0
(-2150 5700);
DISPLAY INVISIBLE (-2150 5700);
FORCEPROP 1 LAST BODY_TYPE PLUMBING
J 0
(-2150 5750);
DISPLAY 0.872340 (-2150 5750);
PAINT GREEN (-2150 5750);
DISPLAY INVISIBLE (-2150 5750);
FORCEPROP 1 LAST HDL_TAP TRUE
J 0
(-1825 5575);
DISPLAY 0.872340 (-1825 5575);
DISPLAY INVISIBLE (-1825 5575);
FORCEPROP 1 LAST PATH I32
J 0
(-2152 5700);
DISPLAY 0.872340 (-2152 5700);
PAINT GREEN (-2152 5700);
DISPLAY INVISIBLE (-2152 5700);
FORCEADD TAP..1
(-1950 4900);
FORCEPROP 3 LASTPIN (-2000 4900) SIG_NAME P5E_CPU1_P2_RX_DN<5>
J 0
(-1990 4910);
DISPLAY 0.659574 (-1990 4910);
PAINT MONO (-1990 4910);
DISPLAY INVISIBLE (-1990 4910);
FORCEPROP 1 LASTPIN (-2000 4900) BN 5
J 0
(-2012 4908);
DISPLAY 0.680851 (-2012 4908);
PAINT GREEN (-2012 4908);
FORCEPROP 2 LAST CDS_LIB standard
J 0
(-1950 4900);
DISPLAY INVISIBLE (-1950 4900);
FORCEPROP 1 LAST BODY_TYPE PLUMBING
J 0
(-1950 4950);
DISPLAY 0.872340 (-1950 4950);
PAINT GREEN (-1950 4950);
DISPLAY INVISIBLE (-1950 4950);
FORCEPROP 1 LAST HDL_TAP TRUE
J 0
(-1625 4775);
DISPLAY 0.872340 (-1625 4775);
DISPLAY INVISIBLE (-1625 4775);
FORCEPROP 1 LAST PATH I33
J 0
(-1952 4900);
DISPLAY 0.872340 (-1952 4900);
PAINT GREEN (-1952 4900);
DISPLAY INVISIBLE (-1952 4900);
FORCEADD TAP..1
(-1950 5600);
FORCEPROP 3 LASTPIN (-2000 5600) SIG_NAME P5E_CPU1_P2_RX_DN<7>
J 0
(-1990 5610);
DISPLAY 0.659574 (-1990 5610);
PAINT MONO (-1990 5610);
DISPLAY INVISIBLE (-1990 5610);
FORCEPROP 1 LASTPIN (-2000 5600) BN 7
J 0
(-2012 5608);
DISPLAY 0.680851 (-2012 5608);
PAINT GREEN (-2012 5608);
FORCEPROP 2 LAST CDS_LIB standard
J 0
(-1950 5600);
DISPLAY INVISIBLE (-1950 5600);
FORCEPROP 1 LAST BODY_TYPE PLUMBING
J 0
(-1950 5650);
DISPLAY 0.872340 (-1950 5650);
PAINT GREEN (-1950 5650);
DISPLAY INVISIBLE (-1950 5650);
FORCEPROP 1 LAST HDL_TAP TRUE
J 0
(-1625 5475);
DISPLAY 0.872340 (-1625 5475);
DISPLAY INVISIBLE (-1625 5475);
FORCEPROP 1 LAST PATH I34
J 0
(-1952 5600);
DISPLAY 0.872340 (-1952 5600);
PAINT GREEN (-1952 5600);
DISPLAY INVISIBLE (-1952 5600);
FORCEADD OFFPAGE..5
R 2
(-950 5625);
FORCEPROP 2 LAST $XR0 52 
J 0
(-761 5625);
DISPLAY 0.638298 (-761 5625);
PAINT MONO (-761 5625);
FORCEPROP 2 LAST CDS_LIB standard
J 0
(-950 5625);
DISPLAY INVISIBLE (-950 5625);
FORCEPROP 1 LAST OFFPAGE TRUE
J 2
(-1275 5500);
DISPLAY 0.872340 (-1275 5500);
PAINT GREEN (-1275 5500);
DISPLAY INVISIBLE (-1275 5500);
FORCEPROP 1 LAST COMMENT_BODY TRUE
J 2
(-1050 5550);
DISPLAY 0.872340 (-1050 5550);
PAINT GREEN (-1050 5550);
DISPLAY INVISIBLE (-1050 5550);
FORCEPROP 2 LAST PATH I35
J 0
(-775 5700);
DISPLAY 0.680851 (-775 5700);
DISPLAY INVISIBLE (-775 5700);
FORCEADD OFFPAGE..5
R 2
(-950 5725);
FORCEPROP 2 LAST $XR0 52 
J 0
(-761 5725);
DISPLAY 0.638298 (-761 5725);
PAINT MONO (-761 5725);
FORCEPROP 2 LAST CDS_LIB standard
J 0
(-950 5725);
DISPLAY INVISIBLE (-950 5725);
FORCEPROP 1 LAST OFFPAGE TRUE
J 2
(-1275 5600);
DISPLAY 0.872340 (-1275 5600);
PAINT GREEN (-1275 5600);
DISPLAY INVISIBLE (-1275 5600);
FORCEPROP 1 LAST COMMENT_BODY TRUE
J 2
(-1050 5650);
DISPLAY 0.872340 (-1050 5650);
PAINT GREEN (-1050 5650);
DISPLAY INVISIBLE (-1050 5650);
FORCEPROP 2 LAST PATH I36
J 0
(-775 5800);
DISPLAY 0.680851 (-775 5800);
DISPLAY INVISIBLE (-775 5800);
FORCEADD TAP..1
(-1950 5250);
FORCEPROP 3 LASTPIN (-2000 5250) SIG_NAME P5E_CPU1_P2_RX_DN<6>
J 0
(-1990 5260);
DISPLAY 0.659574 (-1990 5260);
PAINT MONO (-1990 5260);
DISPLAY INVISIBLE (-1990 5260);
FORCEPROP 1 LASTPIN (-2000 5250) BN 6
J 0
(-2012 5258);
DISPLAY 0.680851 (-2012 5258);
PAINT GREEN (-2012 5258);
FORCEPROP 2 LAST CDS_LIB standard
J 0
(-1950 5250);
DISPLAY INVISIBLE (-1950 5250);
FORCEPROP 1 LAST BODY_TYPE PLUMBING
J 0
(-1950 5300);
DISPLAY 0.872340 (-1950 5300);
PAINT GREEN (-1950 5300);
DISPLAY INVISIBLE (-1950 5300);
FORCEPROP 1 LAST HDL_TAP TRUE
J 0
(-1625 5125);
DISPLAY 0.872340 (-1625 5125);
DISPLAY INVISIBLE (-1625 5125);
FORCEPROP 1 LAST PATH I37
J 0
(-1952 5250);
DISPLAY 0.872340 (-1952 5250);
PAINT GREEN (-1952 5250);
DISPLAY INVISIBLE (-1952 5250);
FORCEADD PT5161LRS..7
(-3175 4450);
FORCEPROP 1 LAST LOCATION U6016
J 0
(-3525 6075);
DISPLAY 0.723404 (-3525 6075);
PAINT GREEN (-3525 6075);
FORCEPROP 0 LAST $SEC 7
J 0
(-3525 6225);
DISPLAY 0.680851 (-3525 6225);
PAINT MONO (-3525 6225);
DISPLAY INVISIBLE (-3525 6225);
FORCEPROP 0 LAST CDS_SEC 7
J 0
(-3525 6225);
DISPLAY 0.680851 (-3525 6225);
DISPLAY INVISIBLE (-3525 6225);
FORCEPROP 0 LASTPIN (-2725 5600) $PN CK29
J 0
(-2715 5610);
DISPLAY 0.680851 (-2715 5610);
PAINT MONO (-2715 5610);
FORCEPROP 0 LASTPIN (-2725 5250) $PN CU29
J 0
(-2715 5260);
DISPLAY 0.680851 (-2715 5260);
PAINT MONO (-2715 5260);
FORCEPROP 0 LASTPIN (-2725 4900) $PN DD29
J 0
(-2715 4910);
DISPLAY 0.680851 (-2715 4910);
PAINT MONO (-2715 4910);
FORCEPROP 0 LASTPIN (-2725 4550) $PN DL29
J 0
(-2715 4560);
DISPLAY 0.680851 (-2715 4560);
PAINT MONO (-2715 4560);
FORCEPROP 0 LASTPIN (-2725 4200) $PN DV29
J 0
(-2715 4210);
DISPLAY 0.680851 (-2715 4210);
PAINT MONO (-2715 4210);
FORCEPROP 0 LASTPIN (-2725 3850) $PN EE29
J 0
(-2715 3860);
DISPLAY 0.680851 (-2715 3860);
PAINT MONO (-2715 3860);
FORCEPROP 0 LASTPIN (-2725 3500) $PN EM29
J 0
(-2715 3510);
DISPLAY 0.680851 (-2715 3510);
PAINT MONO (-2715 3510);
FORCEPROP 0 LASTPIN (-2725 3150) $PN EW29
J 0
(-2715 3160);
DISPLAY 0.680851 (-2715 3160);
PAINT MONO (-2715 3160);
FORCEPROP 0 LASTPIN (-2725 5700) $PN CH26
J 0
(-2715 5710);
DISPLAY 0.680851 (-2715 5710);
PAINT MONO (-2715 5710);
FORCEPROP 0 LASTPIN (-2725 5350) $PN CR26
J 0
(-2715 5360);
DISPLAY 0.680851 (-2715 5360);
PAINT MONO (-2715 5360);
FORCEPROP 0 LASTPIN (-2725 5000) $PN DB26
J 0
(-2715 5010);
DISPLAY 0.680851 (-2715 5010);
PAINT MONO (-2715 5010);
FORCEPROP 0 LASTPIN (-2725 4650) $PN DJ26
J 0
(-2715 4660);
DISPLAY 0.680851 (-2715 4660);
PAINT MONO (-2715 4660);
FORCEPROP 0 LASTPIN (-2725 4300) $PN DT26
J 0
(-2715 4310);
DISPLAY 0.680851 (-2715 4310);
PAINT MONO (-2715 4310);
FORCEPROP 0 LASTPIN (-2725 3950) $PN EC26
J 0
(-2715 3960);
DISPLAY 0.680851 (-2715 3960);
PAINT MONO (-2715 3960);
FORCEPROP 0 LASTPIN (-2725 3600) $PN EK26
J 0
(-2715 3610);
DISPLAY 0.680851 (-2715 3610);
PAINT MONO (-2715 3610);
FORCEPROP 0 LASTPIN (-2725 3250) $PN EU26
J 0
(-2715 3260);
DISPLAY 0.680851 (-2715 3260);
PAINT MONO (-2715 3260);
FORCEPROP 2 LAST PART_TYPE SMLF
J 0
(-3525 6175);
DISPLAY 0.680851 (-3525 6175);
FORCEPROP 2 LAST VALUE PT5161LRS
J 0
(-3525 6125);
DISPLAY 0.680851 (-3525 6125);
FORCEPROP 1 LAST MATERIAL IC
J 0
(-3525 5925);
DISPLAY 0.723404 (-3525 5925);
PAINT GREEN (-3525 5925);
FORCEPROP 1 LAST NEEDS_NO_SIZE TRUE
J 0
(-3175 4450);
DISPLAY 0.723404 (-3175 4450);
PAINT GREEN (-3175 4450);
DISPLAY INVISIBLE (-3175 4450);
FORCEPROP 1 LAST CDS_LMAN_SYM_OUTLINE -350,1450,300,-1400
J 0
(-3175 4450);
DISPLAY 0.468085 (-3175 4450);
PAINT GREEN (-3175 4450);
DISPLAY INVISIBLE (-3175 4450);
FORCEPROP 2 LAST CDS_LIB pure_quanta
J 0
(-3175 4450);
DISPLAY INVISIBLE (-3175 4450);
FORCEPROP 1 LAST PATH I38
J 0
(-3175 4450);
DISPLAY 0.723404 (-3175 4450);
PAINT GREEN (-3175 4450);
DISPLAY INVISIBLE (-3175 4450);
FORCEPROP 1 LAST PART_NUMBER AJ051610U03
J 0
(-3525 6000);
DISPLAY 0.723404 (-3525 6000);
PAINT GREEN (-3525 6000);
DISPLAY INVISIBLE (-3525 6000);
FORCEADD TAP..1
(-6475 3075);
FORCEPROP 3 LASTPIN (-6525 3075) SIG_NAME P5E_CPU1_P2_RX_DN<8>
J 0
(-6515 3085);
DISPLAY 0.659574 (-6515 3085);
PAINT MONO (-6515 3085);
DISPLAY INVISIBLE (-6515 3085);
FORCEPROP 1 LASTPIN (-6525 3075) BN 8
J 0
(-6537 3083);
DISPLAY 0.680851 (-6537 3083);
PAINT GREEN (-6537 3083);
FORCEPROP 2 LAST CDS_LIB standard
J 0
(-6475 3075);
DISPLAY INVISIBLE (-6475 3075);
FORCEPROP 1 LAST BODY_TYPE PLUMBING
J 0
(-6475 3125);
DISPLAY 0.872340 (-6475 3125);
PAINT GREEN (-6475 3125);
DISPLAY INVISIBLE (-6475 3125);
FORCEPROP 1 LAST HDL_TAP TRUE
J 0
(-6150 2950);
DISPLAY 0.872340 (-6150 2950);
DISPLAY INVISIBLE (-6150 2950);
FORCEPROP 1 LAST PATH I4
J 0
(-6477 3075);
DISPLAY 0.872340 (-6477 3075);
PAINT GREEN (-6477 3075);
DISPLAY INVISIBLE (-6477 3075);
FORCEADD TAP..1
(-6475 3425);
FORCEPROP 3 LASTPIN (-6525 3425) SIG_NAME P5E_CPU1_P2_RX_DN<9>
J 0
(-6515 3435);
DISPLAY 0.659574 (-6515 3435);
PAINT MONO (-6515 3435);
DISPLAY INVISIBLE (-6515 3435);
FORCEPROP 1 LASTPIN (-6525 3425) BN 9
J 0
(-6537 3433);
DISPLAY 0.680851 (-6537 3433);
PAINT GREEN (-6537 3433);
FORCEPROP 2 LAST CDS_LIB standard
J 0
(-6475 3425);
DISPLAY INVISIBLE (-6475 3425);
FORCEPROP 1 LAST BODY_TYPE PLUMBING
J 0
(-6475 3475);
DISPLAY 0.872340 (-6475 3475);
PAINT GREEN (-6475 3475);
DISPLAY INVISIBLE (-6475 3475);
FORCEPROP 1 LAST HDL_TAP TRUE
J 0
(-6150 3300);
DISPLAY 0.872340 (-6150 3300);
DISPLAY INVISIBLE (-6150 3300);
FORCEPROP 1 LAST PATH I5
J 0
(-6477 3425);
DISPLAY 0.872340 (-6477 3425);
PAINT GREEN (-6477 3425);
DISPLAY INVISIBLE (-6477 3425);
FORCEADD TAP..1
(-6675 3875);
FORCEPROP 3 LASTPIN (-6725 3875) SIG_NAME P5E_CPU1_P2_RX_DP<10>
J 0
(-6715 3885);
DISPLAY 0.659574 (-6715 3885);
PAINT MONO (-6715 3885);
DISPLAY INVISIBLE (-6715 3885);
FORCEPROP 1 LASTPIN (-6725 3875) BN 10
J 0
(-6737 3883);
DISPLAY 0.680851 (-6737 3883);
PAINT GREEN (-6737 3883);
FORCEPROP 2 LAST CDS_LIB standard
J 0
(-6675 3875);
DISPLAY INVISIBLE (-6675 3875);
FORCEPROP 1 LAST BODY_TYPE PLUMBING
J 0
(-6675 3925);
DISPLAY 0.872340 (-6675 3925);
PAINT GREEN (-6675 3925);
DISPLAY INVISIBLE (-6675 3925);
FORCEPROP 1 LAST HDL_TAP TRUE
J 0
(-6350 3750);
DISPLAY 0.872340 (-6350 3750);
DISPLAY INVISIBLE (-6350 3750);
FORCEPROP 1 LAST PATH I6
J 0
(-6677 3875);
DISPLAY 0.872340 (-6677 3875);
PAINT GREEN (-6677 3875);
DISPLAY INVISIBLE (-6677 3875);
FORCEADD TAP..1
(-6475 3775);
FORCEPROP 3 LASTPIN (-6525 3775) SIG_NAME P5E_CPU1_P2_RX_DN<10>
J 0
(-6515 3785);
DISPLAY 0.659574 (-6515 3785);
PAINT MONO (-6515 3785);
DISPLAY INVISIBLE (-6515 3785);
FORCEPROP 1 LASTPIN (-6525 3775) BN 10
J 0
(-6537 3783);
DISPLAY 0.680851 (-6537 3783);
PAINT GREEN (-6537 3783);
FORCEPROP 2 LAST CDS_LIB standard
J 0
(-6475 3775);
DISPLAY INVISIBLE (-6475 3775);
FORCEPROP 1 LAST BODY_TYPE PLUMBING
J 0
(-6475 3825);
DISPLAY 0.872340 (-6475 3825);
PAINT GREEN (-6475 3825);
DISPLAY INVISIBLE (-6475 3825);
FORCEPROP 1 LAST HDL_TAP TRUE
J 0
(-6150 3650);
DISPLAY 0.872340 (-6150 3650);
DISPLAY INVISIBLE (-6150 3650);
FORCEPROP 1 LAST PATH I7
J 0
(-6477 3775);
DISPLAY 0.872340 (-6477 3775);
PAINT GREEN (-6477 3775);
DISPLAY INVISIBLE (-6477 3775);
FORCEADD TAP..1
(-6675 4225);
FORCEPROP 3 LASTPIN (-6725 4225) SIG_NAME P5E_CPU1_P2_RX_DP<11>
J 0
(-6715 4235);
DISPLAY 0.659574 (-6715 4235);
PAINT MONO (-6715 4235);
DISPLAY INVISIBLE (-6715 4235);
FORCEPROP 1 LASTPIN (-6725 4225) BN 11
J 0
(-6737 4233);
DISPLAY 0.680851 (-6737 4233);
PAINT GREEN (-6737 4233);
FORCEPROP 2 LAST CDS_LIB standard
J 0
(-6675 4225);
DISPLAY INVISIBLE (-6675 4225);
FORCEPROP 1 LAST BODY_TYPE PLUMBING
J 0
(-6675 4275);
DISPLAY 0.872340 (-6675 4275);
PAINT GREEN (-6675 4275);
DISPLAY INVISIBLE (-6675 4275);
FORCEPROP 1 LAST HDL_TAP TRUE
J 0
(-6350 4100);
DISPLAY 0.872340 (-6350 4100);
DISPLAY INVISIBLE (-6350 4100);
FORCEPROP 1 LAST PATH I8
J 0
(-6677 4225);
DISPLAY 0.872340 (-6677 4225);
PAINT GREEN (-6677 4225);
DISPLAY INVISIBLE (-6677 4225);
FORCEADD TAP..1
(-6475 4125);
FORCEPROP 3 LASTPIN (-6525 4125) SIG_NAME P5E_CPU1_P2_RX_DN<11>
J 0
(-6515 4135);
DISPLAY 0.659574 (-6515 4135);
PAINT MONO (-6515 4135);
DISPLAY INVISIBLE (-6515 4135);
FORCEPROP 1 LASTPIN (-6525 4125) BN 11
J 0
(-6537 4133);
DISPLAY 0.680851 (-6537 4133);
PAINT GREEN (-6537 4133);
FORCEPROP 2 LAST CDS_LIB standard
J 0
(-6475 4125);
DISPLAY INVISIBLE (-6475 4125);
FORCEPROP 1 LAST BODY_TYPE PLUMBING
J 0
(-6475 4175);
DISPLAY 0.872340 (-6475 4175);
PAINT GREEN (-6475 4175);
DISPLAY INVISIBLE (-6475 4175);
FORCEPROP 1 LAST HDL_TAP TRUE
J 0
(-6150 4000);
DISPLAY 0.872340 (-6150 4000);
DISPLAY INVISIBLE (-6150 4000);
FORCEPROP 1 LAST PATH I9
J 0
(-6477 4125);
DISPLAY 0.872340 (-6477 4125);
PAINT GREEN (-6477 4125);
DISPLAY INVISIBLE (-6477 4125);
FORCEADD QUANTA_TITLE_BLOCK_C..1
(0 0);
FORCEPROP 0 LAST CDS_CON_LAST_MODIFIED Thu Sep 14 16:12:55 2023
J 0
(-1885 15);
DISPLAY INVISIBLE (-1885 15);
FORCEPROP 1 LAST CUSTOM_TXT_CDS <CON_LAST_MODIFIED>
J 0
(-1885 15);
DISPLAY 0.978723 (-1885 15);
FORCEPROP 2 LAST CUSTOM_TXT_CDS <XR_PAGE_TITLE>
J 0
(-7890 5250);
DISPLAY 0.638298 (-7890 5250);
PAINT PINK (-7890 5250);
DISPLAY INVISIBLE (-7890 5250);
FORCEPROP 1 LAST CUSTOM_TXT_CDS <NAME_2>
J 0
(-3175 50);
FORCEPROP 1 LAST CUSTOM_TXT_CDS <NAME_1>
J 0
(-3175 175);
FORCEPROP 1 LAST CUSTOM_TXT_CDS <Q_NUMBER>
J 0
(-1403 103);
DISPLAY 1.212766 (-1403 103);
FORCEPROP 1 LAST CUSTOM_TXT_CDS <Q_PROJ>
J 0
(-2382 102);
DISPLAY 1.212766 (-2382 102);
FORCEPROP 1 LAST CUSTOM_TXT_CDS <Q_REV>
J 0
(-184 103);
DISPLAY 1.212766 (-184 103);
FORCEPROP 1 LAST CUSTOM_TXT_CDS <CON_PAGE_NUM> OF <CON_TOTAL_PAGES>
J 0
(-446 18);
DISPLAY 0.978723 (-446 18);
FORCEPROP 1 LAST Q_TITLE RETIMER_CPU1_P2(2)
J 0
(-9366 26);
DISPLAY 2.446809 (-9366 26);
PAINT GREEN (-9366 26);
FORCEPROP 2 LAST CDS_LIB pure_quanta
J 0
(0 0);
DISPLAY INVISIBLE (0 0);
FORCEPROP 1 LAST CDS_LMAN_SYM_OUTLINE -9475,6775,100,-125
J 0
(0 0);
DISPLAY 0.468085 (0 0);
PAINT GREEN (0 0);
DISPLAY INVISIBLE (0 0);
FORCEPROP 2 LAST PAGE_BORDER TRUE
J 0
(-7890 5250);
DISPLAY 0.638298 (-7890 5250);
PAINT PINK (-7890 5250);
DISPLAY INVISIBLE (-7890 5250);
FORCEPROP 2 LAST CDS_XR_PAGE_TITLE CR-340 : @T6G_MB_LIB.T6G(SCH_1):PAGE340
J 0
(-7890 5250);
DISPLAY 0.638298 (-7890 5250);
PAINT PINK (-7890 5250);
DISPLAY INVISIBLE (-7890 5250);
FORCEPROP 1 LAST Q_DEPT BU9
J 1
(-3763 49);
DISPLAY 1.957447 (-3763 49);
PAINT GREEN (-3763 49);
DISPLAY INVISIBLE (-3763 49);
FORCEPROP 1 LAST COMMENT_BODY TRUE
J 0
(12 -13);
DISPLAY 0.978723 (12 -13);
PAINT GREEN (12 -13);
DISPLAY INVISIBLE (12 -13);
WIRE 17 -1 (-6625 4250)(-6625 3900);
WIRE 17 -1 (-6625 4250)(-6625 4600);
WIRE 17 -1 (-6625 3900)(-6625 3550);
WIRE 17 -1 (-6625 3550)(-6625 3200);
WIRE 17 -1 (-6625 4950)(-6625 4600);
WIRE 17 -1 (-6625 5300)(-6625 4950);
WIRE 17 -1 (-6625 5650)(-6625 5300);
WIRE 17 -1 (-6625 5950)(-6625 5650);
WIRE 17 -1 (-6625 5950)(-5500 5950);
FORCEPROP 2 LAST SIG_NAME P5E_CPU1_P2_RX_DP<15:8>
J 0
(-6360 5960);
DISPLAY 0.680851 (-6360 5960);
PAINT WHITE (-6360 5960);
WIRE 17 -1 (-2100 4325)(-2100 4675);
WIRE 17 -1 (-2100 4325)(-2100 3975);
WIRE 17 -1 (-2100 5025)(-2100 4675);
WIRE 17 -1 (-2100 5375)(-2100 5025);
WIRE 17 -1 (-2100 3975)(-2100 3625);
WIRE 17 -1 (-2100 3625)(-2100 3275);
WIRE 17 -1 (-2100 5725)(-2100 5375);
WIRE 17 -1 (-2100 5725)(-1000 5725);
FORCEPROP 2 LAST SIG_NAME P5E_CPU1_P2_RX_DP<7:0>
J 0
(-1835 5735);
DISPLAY 0.680851 (-1835 5735);
PAINT WHITE (-1835 5735);
WIRE 17 -1 (-1900 5625)(-1000 5625);
FORCEPROP 2 LAST SIG_NAME P5E_CPU1_P2_RX_DN<7:0>
J 0
(-1835 5635);
DISPLAY 0.680851 (-1835 5635);
PAINT WHITE (-1835 5635);
WIRE 17 -1 (-1900 4225)(-1900 3875);
WIRE 17 -1 (-1900 4225)(-1900 4575);
WIRE 17 -1 (-1900 3875)(-1900 3525);
WIRE 17 -1 (-1900 3525)(-1900 3175);
WIRE 17 -1 (-1900 4925)(-1900 4575);
WIRE 17 -1 (-1900 5275)(-1900 4925);
WIRE 17 -1 (-1900 5625)(-1900 5275);
WIRE 17 -1 (-6425 4150)(-6425 3800);
WIRE 17 -1 (-6425 4150)(-6425 4500);
WIRE 17 -1 (-6425 3800)(-6425 3450);
WIRE 17 -1 (-6425 3450)(-6425 3100);
WIRE 17 -1 (-6425 4850)(-6425 4500);
WIRE 17 -1 (-6425 5200)(-6425 4850);
WIRE 17 -1 (-6425 5550)(-6425 5200);
WIRE 17 -1 (-6425 5800)(-6425 5550);
WIRE 17 -1 (-6425 5800)(-5500 5800);
FORCEPROP 2 LAST SIG_NAME P5E_CPU1_P2_RX_DN<15:8>
J 0
(-6360 5810);
DISPLAY 0.680851 (-6360 5810);
PAINT WHITE (-6360 5810);
WIRE 16 -1 (-7250 5625)(-6725 5625);
WIRE 16 -1 (-7250 5525)(-6525 5525);
WIRE 16 -1 (-7250 5275)(-6725 5275);
WIRE 16 -1 (-7250 5175)(-6525 5175);
WIRE 16 -1 (-7250 4125)(-6525 4125);
WIRE 16 -1 (-7250 4475)(-6525 4475);
WIRE 16 -1 (-7250 3425)(-6525 3425);
WIRE 16 -1 (-7250 3075)(-6525 3075);
WIRE 16 -1 (-7250 4825)(-6525 4825);
WIRE 16 -1 (-7250 3775)(-6525 3775);
WIRE 16 -1 (-2725 4200)(-2000 4200);
WIRE 16 -1 (-2725 3150)(-2000 3150);
WIRE 16 -1 (-2725 3500)(-2000 3500);
WIRE 16 -1 (-2725 5250)(-2000 5250);
WIRE 16 -1 (-2725 4900)(-2000 4900);
WIRE 16 -1 (-2725 4550)(-2000 4550);
WIRE 16 -1 (-2725 3850)(-2000 3850);
WIRE 16 -1 (-2725 5600)(-2000 5600);
WIRE 16 -1 (-2725 5000)(-2200 5000);
WIRE 16 -1 (-2725 5350)(-2200 5350);
WIRE 16 -1 (-2725 3250)(-2200 3250);
WIRE 16 -1 (-2725 3600)(-2200 3600);
WIRE 16 -1 (-2725 3950)(-2200 3950);
WIRE 16 -1 (-2725 4650)(-2200 4650);
WIRE 16 -1 (-2725 5700)(-2200 5700);
WIRE 16 -1 (-2725 4300)(-2200 4300);
WIRE 16 -1 (-7250 4925)(-6725 4925);
WIRE 16 -1 (-7250 4575)(-6725 4575);
WIRE 16 -1 (-7250 4225)(-6725 4225);
WIRE 16 -1 (-7250 3175)(-6725 3175);
WIRE 16 -1 (-7250 3525)(-6725 3525);
WIRE 16 -1 (-7250 3875)(-6725 3875);
FORCENOTE
P5E_CPU1_P2_RX_DP/DN<0-15> LANE REVERSAL
(-9050 6275) 0;
DISPLAY LEFT (-9050 6275);
DISPLAY 2.000000 (-9050 6275);
FORCENOTE
RETIMER TO CPU
(-3575 2650) 0;
DISPLAY LEFT (-3575 2650);
DISPLAY 3.148936 (-3575 2650);
FORCENOTE
RETIMER TO CPU
(-8050 2675) 0;
DISPLAY LEFT (-8050 2675);
DISPLAY 3.148936 (-8050 2675);
QUIT
